#ISCELL
  logical_power cad_note *
  *
#ISCELL
  logical_power design_note *
  *
#ISCELL
  mstr_misc dns *
  *
#ISCELL
  pure_quanta quanta_title_block_c *
  *
#CELL
  pure_quanta q_cap *
  page51_i1
#ISCELL
  logical_power universal_gnd *
  page51_i10
#ISCELL
  logical_power universal_gnd *
  page51_i12
#CELL
  pure_quanta q_cap *
  page51_i13
#ISCELL
  logical_power universal_gnd *
  page51_i14
#ISCELL
  logical_power universal_gnd *
  page51_i19
#ISCELL
  logical_power universal_gnd *
  page51_i2
#ISCELL
  logical_power universal_gnd *
  page51_i20
#CELL
  pure_quanta q_res *
  page51_i21
#CELL
  pure_quanta q_cap *
  page51_i22
#CELL
  pure_quanta q_cap *
  page51_i23
#ISCELL
  logical_power vccaux15 *
  page51_i24
#ISCELL
  logical_power universal_gnd *
  page51_i25
#CELL
  pure_quanta q_res *
  page51_i26
#CELL
  pure_quanta q_cap *
  page51_i27
#CELL
  pure_quanta q_inductor *
  page51_i28
#CELL
  pure_quanta q_res *
  page51_i3
#CELL
  pure_quanta q_res *
  page51_i30
#CELL
  pure_quanta q_cap *
  page51_i31
#CELL
  pure_quanta q_cap *
  page51_i32
#CELL
  pure_quanta q_cap *
  page51_i33
#ISCELL
  logical_power universal_gnd *
  page51_i35
#CELL
  pure_quanta q_cap *
  page51_i36
#CELL
  pure_quanta q_cap *
  page51_i37
#ISCELL
  logical_power vccaux15 *
  page51_i38
#CELL
  pure_quanta q_inductor *
  page51_i39
#CELL
  pure_quanta q_res *
  page51_i4
#CELL
  pure_quanta mpq8633aglec807z *
  page51_i42
#CELL
  pure_quanta q_res *
  page51_i43
#ISCELL
  logical_power universal_gnd *
  page51_i44
#CELL
  pure_quanta q_cap *
  page51_i45
#ISCELL
  standard offpage *
  page51_i46
#CELL
  pure_quanta q_cap *
  page51_i47
#CELL
  pure_quanta q_cap *
  page51_i48
#CELL
  pure_quanta q_cap *
  page51_i49
#ISCELL
  logical_power vccaux15 *
  page51_i5
#ISCELL
  logical_power universal_gnd *
  page51_i50
#CELL
  pure_quanta q_res *
  page51_i51
#CELL
  pure_quanta q_cap *
  page51_i52
#ISCELL
  logical_power universal_gnd *
  page51_i53
#CELL
  pure_quanta q_res *
  page51_i54
#ISCELL
  standard offpage *
  page51_i55
#CELL
  pure_quanta ap2205w57 *
  page51_i56
#CELL
  pure_quanta q_res *
  page51_i57
#ISCELL
  logical_power universal_gnd *
  page51_i58
#ISCELL
  logical_power universal_power *
  page51_i59
#ISCELL
  logical_power vccaux15 *
  page51_i6
#CELL
  pure_quanta q_cap *
  page51_i60
#ISCELL
  logical_power universal_gnd *
  page51_i61
#CELL
  pure_quanta q_res *
  page51_i62
#ISCELL
  logical_power universal_gnd *
  page51_i63
#ISCELL
  logical_power universal_gnd *
  page51_i65
#ISCELL
  logical_power universal_power *
  page51_i66
#CELL
  pure_quanta q_cap *
  page51_i68
#ISCELL
  logical_power universal_gnd *
  page51_i8
#CELL
  pure_quanta q_res *
  page51_i9
